(kicad_pcb
	(version 20260206)
	(generator "pcbnew")
	(generator_version "10.0")
	(general
		(thickness 1.6)
		(legacy_teardrops no)
	)
	(paper "A4")
	(title_block
		(title "dpb — 14545-sa.0730WZS0815.brd")
		(comment 1 "Honey Badger (Wiwynn) / footprints 1037-1043 of 1066")
	)
	(layers
		(0 "F.Cu" signal "TOP")
		(4 "In1.Cu" signal "L2GND")
		(6 "In2.Cu" signal "L3")
		(8 "In3.Cu" signal "L4VCC")
		(10 "In4.Cu" signal "L5VCC")
		(12 "In5.Cu" signal "L6")
		(14 "In6.Cu" signal "L7GND")
		(2 "B.Cu" signal "BOTTOM")
		(9 "F.Adhes" user "F.Adhesive")
		(11 "B.Adhes" user "B.Adhesive")
		(13 "F.Paste" user "Package Geometry/Pastemask Top")
		(15 "B.Paste" user "Package Geometry/Pastemask Bottom")
		(5 "F.SilkS" user "Ref Des/Silkscreen Top")
		(7 "B.SilkS" user "Ref Des/Silkscreen Bottom")
		(1 "F.Mask" user "Board Geometry/Soldermask Top")
		(3 "B.Mask" user "Board Geometry/Soldermask Bottom")
		(17 "Dwgs.User" user "User.Drawings")
		(19 "Cmts.User" user "User.Comments")
		(21 "Eco1.User" user "User.Eco1")
		(23 "Eco2.User" user "User.Eco2")
		(25 "Edge.Cuts" user "Board Geometry/Outline")
		(27 "Margin" user)
		(31 "F.CrtYd" user "Package Geometry/Place Bound Top")
		(29 "B.CrtYd" user "Package Geometry/Place Bound Bottom")
		(35 "F.Fab" user "Ref Des/Assembly Top")
		(33 "B.Fab" user "Ref Des/Assembly Bottom")
	)
	(footprint ""
		(layer "F.Cu")
		(at 85.344 -499.618 180)
		(property "Reference" "D20"
			(at 0 0 180)
			(layer "F.SilkS")
			(hide yes)
			(effects
				(font
					(size 1.27 1.27)
				)
			)
		)
		(property "Value" "RB551V30-1-GP"
			(at 0 -6.7818 180)
			(unlocked yes)
			(layer "F.Fab")
			(hide yes)
			(effects
				(font
					(size 1.016 1.016)
					(thickness 0.1524)
				)
			)
		)
		(property "Device Type" "SOD323AKH44"
			(at 0 -8.6868 180)
			(unlocked yes)
			(layer "F.Fab")
			(hide yes)
			(effects
				(font
					(size 1.016 1.016)
					(thickness 0.1524)
				)
			)
		)
		(duplicate_pad_numbers_are_jumpers no)
		(fp_line
			(start 0.889 2.159)
			(end -0.889 2.159)
			(stroke
				(width 0.1524)
				(type default)
			)
			(layer "F.SilkS")
		)
		(fp_line
			(start 0.889 -1.9304)
			(end 0.889 2.159)
			(stroke
				(width 0.1524)
				(type default)
			)
			(layer "F.SilkS")
		)
		(fp_line
			(start 0.762 2.0574)
			(end -0.762 2.0574)
			(stroke
				(width 0.508)
				(type default)
			)
			(layer "F.SilkS")
		)
		(fp_line
			(start -0.889 2.159)
			(end -0.889 -1.9304)
			(stroke
				(width 0.1524)
				(type default)
			)
			(layer "F.SilkS")
		)
		(fp_line
			(start -0.889 -1.9304)
			(end 0.889 -1.9304)
			(stroke
				(width 0.1524)
				(type default)
			)
			(layer "F.SilkS")
		)
		(fp_rect
			(start -1.016 2.3114)
			(end 1.016 -2.0066)
			(stroke
				(width 0)
				(type default)
			)
			(fill no)
			(layer "F.CrtYd")
		)
		(fp_poly
			(pts
				(xy -1.016 -2.0066) (xy 1.016 -2.0066) (xy 1.016 2.3114) (xy -1.016 2.3114)
			)
			(stroke
				(width 0)
				(type default)
			)
			(fill no)
			(layer "F.Fab")
		)
		(pad "A" smd rect
			(at 0 -1.143 180)
			(size 0.5588 1.016)
			(layers "F.Cu" "F.Mask" "F.Paste")
			(net "SW_HDD5_R")
		)
		(pad "K" smd rect
			(at 0 1.143 180)
			(size 0.5588 1.016)
			(layers "F.Cu" "F.Mask" "F.Paste")
			(net "SW_HDD5_N")
		)
	)
	(footprint ""
		(layer "F.Cu")
		(at 26.288746 -480.1997 90)
		(property "Reference" "PTC5"
			(at 0 0 90)
			(layer "F.SilkS")
			(hide yes)
			(effects
				(font
					(size 1.27 1.27)
				)
			)
		)
		(property "Value" "ST330U10VDM-2GP"
			(at 0 -9.6012 90)
			(unlocked yes)
			(layer "F.Fab")
			(hide yes)
			(effects
				(font
					(size 1.016 1.016)
					(thickness 0.1524)
				)
			)
		)
		(property "Device Type" "CT7343H150"
			(at 0 -11.1252 90)
			(unlocked yes)
			(layer "F.Fab")
			(hide yes)
			(effects
				(font
					(size 1.016 1.016)
					(thickness 0.1524)
				)
			)
		)
		(duplicate_pad_numbers_are_jumpers no)
		(fp_line
			(start 2.286 -4.8768)
			(end -2.286 -4.8768)
			(stroke
				(width 0.1524)
				(type default)
			)
			(layer "F.SilkS")
		)
		(fp_line
			(start -2.286 -4.8768)
			(end -2.286 -2.032)
			(stroke
				(width 0.1524)
				(type default)
			)
			(layer "F.SilkS")
		)
		(fp_line
			(start 2.1082 -4.699)
			(end -2.1082 -4.699)
			(stroke
				(width 0.508)
				(type default)
			)
			(layer "F.SilkS")
		)
		(fp_line
			(start 2.286 -2.032)
			(end 2.286 -4.8768)
			(stroke
				(width 0.1524)
				(type default)
			)
			(layer "F.SilkS")
		)
		(fp_line
			(start 2.286 2.032)
			(end 2.286 4.8768)
			(stroke
				(width 0.1524)
				(type default)
			)
			(layer "F.SilkS")
		)
		(fp_line
			(start 2.286 4.8768)
			(end -2.286 4.8768)
			(stroke
				(width 0.1524)
				(type default)
			)
			(layer "F.SilkS")
		)
		(fp_line
			(start -2.286 4.8768)
			(end -2.286 2.032)
			(stroke
				(width 0.1524)
				(type default)
			)
			(layer "F.SilkS")
		)
		(fp_rect
			(start -2.1463 3.6449)
			(end 2.1463 -3.6449)
			(stroke
				(width 0)
				(type default)
			)
			(fill no)
			(layer "F.CrtYd")
		)
		(fp_poly
			(pts
				(xy -2.54 4.953) (xy -2.54 4.2926) (xy -3.81 4.2926) (xy -3.81 -4.2926) (xy -2.54 -4.2926) (xy -2.54 -4.953)
				(xy 2.54 -4.953) (xy 2.54 -4.2926) (xy 3.81 -4.2926) (xy 3.81 -1.6256) (xy 2.1463 -1.6256) (xy 2.1463 -3.6449)
				(xy -2.1463 -3.6449) (xy -2.1463 3.6449) (xy 2.1463 3.6449) (xy 2.1463 -1.6129) (xy 3.81 -1.6129)
				(xy 3.81 4.2926) (xy 2.54 4.2926) (xy 2.54 4.953)
			)
			(stroke
				(width 0)
				(type default)
			)
			(fill no)
			(layer "F.CrtYd")
		)
		(fp_rect
			(start 2.54 4.2926)
			(end 3.81 -4.2926)
			(stroke
				(width 0)
				(type default)
			)
			(fill no)
			(layer "F.Fab")
		)
		(fp_rect
			(start -3.81 4.2926)
			(end -2.54 -4.2926)
			(stroke
				(width 0)
				(type default)
			)
			(fill no)
			(layer "F.Fab")
		)
		(fp_rect
			(start -2.54 4.953)
			(end 2.54 -4.953)
			(stroke
				(width 0)
				(type default)
			)
			(fill no)
			(layer "F.Fab")
		)
		(pad "1" smd rect
			(at 0 -3.1496 90)
			(size 2.413 2.286)
			(layers "F.Cu" "F.Mask" "F.Paste")
			(net "P5VC")
		)
		(pad "2" smd rect
			(at 0 3.1496 90)
			(size 2.413 2.286)
			(layers "F.Cu" "F.Mask" "F.Paste")
			(net "GND")
		)
		(zone
			(layer "F.Cu")
			(hatch none 0.5)
			(connect_pads
				(clearance 0)
			)
			(min_thickness 0.25)
			(keepout
				(tracks allowed)
				(vias not_allowed)
				(pads allowed)
				(copperpour not_allowed)
				(footprints allowed)
			)
			(placement
				(enabled no)
				(sheetname "")
			)
			(fill
				(thermal_gap 0.5)
				(thermal_bridge_width 0.5)
				(island_removal_mode 0)
			)
			(polygon
				(pts
					(xy 24.599646 -481.711) (xy 21.691346 -481.711) (xy 21.691346 -478.6884) (xy 24.586946 -478.6884)
					(xy 24.917146 -478.6884) (xy 24.917146 -481.711)
				)
			)
		)
		(zone
			(layer "F.Cu")
			(hatch none 0.5)
			(connect_pads
				(clearance 0)
			)
			(min_thickness 0.25)
			(keepout
				(tracks allowed)
				(vias not_allowed)
				(pads allowed)
				(copperpour not_allowed)
				(footprints allowed)
			)
			(placement
				(enabled no)
				(sheetname "")
			)
			(fill
				(thermal_gap 0.5)
				(thermal_bridge_width 0.5)
				(island_removal_mode 0)
			)
			(polygon
				(pts
					(xy 30.886146 -478.6884) (xy 30.886146 -481.711) (xy 27.990546 -481.711) (xy 27.660346 -481.711)
					(xy 27.660346 -478.6884) (xy 27.990546 -478.6884)
				)
			)
		)
	)
	(footprint ""
		(layer "F.Cu")
		(at 195.58 -191.262 180)
		(property "Reference" "C382"
			(at 0 0 180)
			(layer "F.SilkS")
			(hide yes)
			(effects
				(font
					(size 1.27 1.27)
				)
			)
		)
		(property "Value" "SCD033U25V2KX-GP"
			(at 1.1811 -2.7051 180)
			(unlocked yes)
			(layer "F.Fab")
			(hide yes)
			(effects
				(font
					(size 1.016 1.016)
					(thickness 0.1524)
				)
			)
		)
		(property "Device Type" "C402H22"
			(at 1.1811 -4.2291 180)
			(unlocked yes)
			(layer "F.Fab")
			(hide yes)
			(effects
				(font
					(size 1.016 1.016)
					(thickness 0.1524)
				)
			)
		)
		(duplicate_pad_numbers_are_jumpers no)
		(fp_rect
			(start -0.4318 0.9525)
			(end 0.4318 -0.9525)
			(stroke
				(width 0)
				(type default)
			)
			(fill no)
			(layer "F.CrtYd")
		)
		(fp_rect
			(start -0.4318 0.9525)
			(end 0.4318 -0.9525)
			(stroke
				(width 0)
				(type default)
			)
			(fill no)
			(layer "F.Fab")
		)
		(pad "1" smd custom
			(at 0 -0.4445 180)
			(size 0.1524 0.1524)
			(layers "F.Cu" "F.Mask" "F.Paste")
			(net "SW_HDD3_N")
			(options
				(clearance outline)
				(anchor circle)
			)
			(primitives
				(gr_poly
					(pts
						(arc
							(start 0.3048 -0.2032)
							(mid 0.275042 -0.275042)
							(end 0.2032 -0.3048)
						)
						(arc
							(start -0.2032 -0.3048)
							(mid -0.275042 -0.275042)
							(end -0.3048 -0.2032)
						)
						(arc
							(start -0.3048 0.2032)
							(mid -0.275042 0.275042)
							(end -0.2032 0.3048)
						)
						(arc
							(start 0.2032 0.3048)
							(mid 0.275042 0.275042)
							(end 0.3048 0.2032)
						)
					)
					(width 0)
					(fill yes)
				)
			)
		)
		(pad "2" smd custom
			(at 0 0.4445 180)
			(size 0.1524 0.1524)
			(layers "F.Cu" "F.Mask" "F.Paste")
			(net "P12V")
			(options
				(clearance outline)
				(anchor circle)
			)
			(primitives
				(gr_poly
					(pts
						(arc
							(start 0.3048 -0.2032)
							(mid 0.275042 -0.275042)
							(end 0.2032 -0.3048)
						)
						(arc
							(start -0.2032 -0.3048)
							(mid -0.275042 -0.275042)
							(end -0.3048 -0.2032)
						)
						(arc
							(start -0.3048 0.2032)
							(mid -0.275042 0.275042)
							(end -0.2032 0.3048)
						)
						(arc
							(start 0.2032 0.3048)
							(mid 0.275042 0.275042)
							(end 0.3048 0.2032)
						)
					)
					(width 0)
					(fill yes)
				)
			)
		)
	)
	(footprint ""
		(layer "F.Cu")
		(at 34.543746 -108.486702 90)
		(property "Reference" "R473"
			(at 0 0 90)
			(layer "F.SilkS")
			(hide yes)
			(effects
				(font
					(size 1.27 1.27)
				)
			)
		)
		(property "Value" "4K7R2J-2-GP"
			(at 0.064008 -3.993896 90)
			(unlocked yes)
			(layer "F.Fab")
			(hide yes)
			(effects
				(font
					(size 1.016 1.016)
					(thickness 0.1524)
				)
			)
		)
		(property "Device Type" "R402H16"
			(at 0.064008 -5.517896 90)
			(unlocked yes)
			(layer "F.Fab")
			(hide yes)
			(effects
				(font
					(size 1.016 1.016)
					(thickness 0.1524)
				)
			)
		)
		(duplicate_pad_numbers_are_jumpers no)
		(fp_line
			(start 0.508 -0.9398)
			(end -0.508 -0.9398)
			(stroke
				(width 0.1524)
				(type default)
			)
			(layer "F.SilkS")
		)
		(fp_line
			(start -0.508 -0.9398)
			(end -0.508 0.9398)
			(stroke
				(width 0.1524)
				(type default)
			)
			(layer "F.SilkS")
		)
		(fp_rect
			(start -0.508 0.9398)
			(end 0.508 -0.9398)
			(stroke
				(width 0)
				(type default)
			)
			(fill no)
			(layer "F.CrtYd")
		)
		(fp_rect
			(start -0.508 0.9398)
			(end 0.508 -0.9398)
			(stroke
				(width 0)
				(type default)
			)
			(fill no)
			(layer "F.Fab")
		)
		(pad "1" smd custom
			(at 0 -0.4445 90)
			(size 0.1397 0.1397)
			(layers "F.Cu" "F.Mask" "F.Paste")
			(net "P3V3")
			(options
				(clearance outline)
				(anchor circle)
			)
			(primitives
				(gr_poly
					(pts
						(arc
							(start -0.1778 -0.2794)
							(mid -0.249642 -0.249642)
							(end -0.2794 -0.1778)
						)
						(arc
							(start -0.2794 0.1778)
							(mid -0.249642 0.249642)
							(end -0.1778 0.2794)
						)
						(arc
							(start 0.1778 0.2794)
							(mid 0.249642 0.249642)
							(end 0.2794 0.1778)
						)
						(arc
							(start 0.2794 -0.1778)
							(mid 0.249642 -0.249642)
							(end 0.1778 -0.2794)
						)
					)
					(width 0)
					(fill yes)
				)
			)
		)
		(pad "2" smd custom
			(at 0 0.4445 90)
			(size 0.1397 0.1397)
			(layers "F.Cu" "F.Mask" "F.Paste")
			(net "SAS_EXP_B_PWR13")
			(options
				(clearance outline)
				(anchor circle)
			)
			(primitives
				(gr_poly
					(pts
						(arc
							(start -0.1778 -0.2794)
							(mid -0.249642 -0.249642)
							(end -0.2794 -0.1778)
						)
						(arc
							(start -0.2794 0.1778)
							(mid -0.249642 0.249642)
							(end -0.1778 0.2794)
						)
						(arc
							(start 0.1778 0.2794)
							(mid 0.249642 0.249642)
							(end 0.2794 0.1778)
						)
						(arc
							(start 0.2794 -0.1778)
							(mid 0.249642 -0.249642)
							(end 0.1778 -0.2794)
						)
					)
					(width 0)
					(fill yes)
				)
			)
		)
	)
	(footprint ""
		(layer "F.Cu")
		(at 193.669412 -86.213696 -90)
		(property "Reference" "Q10"
			(at 0 0 270)
			(layer "F.SilkS")
			(hide yes)
			(effects
				(font
					(size 1.27 1.27)
				)
			)
		)
		(property "Value" "2N7002DW-7F-GP"
			(at -2.3622 -8.2042 270)
			(unlocked yes)
			(layer "F.Fab")
			(hide yes)
			(effects
				(font
					(size 1.016 1.016)
					(thickness 0.1524)
				)
			)
		)
		(property "Device Type" "SOT-363H44"
			(at -2.3622 -10.1092 270)
			(unlocked yes)
			(layer "F.Fab")
			(hide yes)
			(effects
				(font
					(size 1.016 1.016)
					(thickness 0.1524)
				)
			)
		)
		(duplicate_pad_numbers_are_jumpers no)
		(fp_line
			(start -1.4478 1.7018)
			(end 1.4478 1.7018)
			(stroke
				(width 0.1524)
				(type default)
			)
			(layer "F.SilkS")
		)
		(fp_line
			(start 1.4478 1.7018)
			(end 1.4478 -1.7018)
			(stroke
				(width 0.1524)
				(type default)
			)
			(layer "F.SilkS")
		)
		(fp_line
			(start -1.27 1.524)
			(end -1.27 0.6604)
			(stroke
				(width 0.4826)
				(type default)
			)
			(layer "F.SilkS")
		)
		(fp_line
			(start -1.4478 -1.7018)
			(end -1.4478 1.7018)
			(stroke
				(width 0.1524)
				(type default)
			)
			(layer "F.SilkS")
		)
		(fp_line
			(start 1.4478 -1.7018)
			(end -1.4478 -1.7018)
			(stroke
				(width 0.1524)
				(type default)
			)
			(layer "F.SilkS")
		)
		(fp_poly
			(pts
				(xy -1.524 -1.778) (xy 1.524 -1.778) (xy 1.524 1.778) (xy -1.524 1.778)
			)
			(stroke
				(width 0)
				(type default)
			)
			(fill no)
			(layer "F.CrtYd")
		)
		(fp_poly
			(pts
				(xy -1.524 -1.778) (xy 1.524 -1.778) (xy 1.524 1.778) (xy -1.524 1.778)
			)
			(stroke
				(width 0)
				(type default)
			)
			(fill no)
			(layer "F.Fab")
		)
		(pad "1" smd rect
			(at -0.65024 0.9398 270)
			(size 0.4064 1.016)
			(layers "F.Cu" "F.Mask" "F.Paste")
			(net "GND")
		)
		(pad "2" smd rect
			(at 0 0.9398 270)
			(size 0.4064 1.016)
			(layers "F.Cu" "F.Mask" "F.Paste")
			(net "SW_PWR_R_HDD4")
		)
		(pad "3" smd rect
			(at 0.65024 0.9398 270)
			(size 0.4064 1.016)
			(layers "F.Cu" "F.Mask" "F.Paste")
			(net "SW_HDD4_P")
		)
		(pad "4" smd rect
			(at 0.65024 -0.9398 270)
			(size 0.4064 1.016)
			(layers "F.Cu" "F.Mask" "F.Paste")
			(net "GND")
		)
		(pad "5" smd rect
			(at 0 -0.9398 270)
			(size 0.4064 1.016)
			(layers "F.Cu" "F.Mask" "F.Paste")
			(net "SW_HDD4_G")
		)
		(pad "6" smd rect
			(at -0.65024 -0.9398 270)
			(size 0.4064 1.016)
			(layers "F.Cu" "F.Mask" "F.Paste")
			(net "SW_HDD4_R")
		)
	)
	(footprint ""
		(layer "F.Cu")
		(at 7.746746 -403.95144 180)
		(property "Reference" "R358"
			(at 0 0 180)
			(layer "F.SilkS")
			(hide yes)
			(effects
				(font
					(size 1.27 1.27)
				)
			)
		)
		(property "Value" "100R2J-2-GP"
			(at 0.064008 -3.993896 180)
			(unlocked yes)
			(layer "F.Fab")
			(hide yes)
			(effects
				(font
					(size 1.016 1.016)
					(thickness 0.1524)
				)
			)
		)
		(property "Device Type" "R402H14"
			(at 0.064008 -5.517896 180)
			(unlocked yes)
			(layer "F.Fab")
			(hide yes)
			(effects
				(font
					(size 1.016 1.016)
					(thickness 0.1524)
				)
			)
		)
		(duplicate_pad_numbers_are_jumpers no)
		(fp_line
			(start 0.508 -0.9398)
			(end -0.508 -0.9398)
			(stroke
				(width 0.1524)
				(type default)
			)
			(layer "F.SilkS")
		)
		(fp_line
			(start -0.508 -0.9398)
			(end -0.508 0.9398)
			(stroke
				(width 0.1524)
				(type default)
			)
			(layer "F.SilkS")
		)
		(fp_rect
			(start -0.508 0.9398)
			(end 0.508 -0.9398)
			(stroke
				(width 0)
				(type default)
			)
			(fill no)
			(layer "F.CrtYd")
		)
		(fp_rect
			(start -0.508 0.9398)
			(end 0.508 -0.9398)
			(stroke
				(width 0)
				(type default)
			)
			(fill no)
			(layer "F.Fab")
		)
		(pad "1" smd custom
			(at 0 -0.4445 180)
			(size 0.1397 0.1397)
			(layers "F.Cu" "F.Mask" "F.Paste")
			(net "TEMP_SENSOR_A_ADDR0&ID")
			(options
				(clearance outline)
				(anchor circle)
			)
			(primitives
				(gr_poly
					(pts
						(arc
							(start -0.1778 -0.2794)
							(mid -0.249642 -0.249642)
							(end -0.2794 -0.1778)
						)
						(arc
							(start -0.2794 0.1778)
							(mid -0.249642 0.249642)
							(end -0.1778 0.2794)
						)
						(arc
							(start 0.1778 0.2794)
							(mid 0.249642 0.249642)
							(end 0.2794 0.1778)
						)
						(arc
							(start 0.2794 -0.1778)
							(mid 0.249642 -0.249642)
							(end 0.1778 -0.2794)
						)
					)
					(width 0)
					(fill yes)
				)
			)
		)
		(pad "2" smd custom
			(at 0 0.4445 180)
			(size 0.1397 0.1397)
			(layers "F.Cu" "F.Mask" "F.Paste")
			(net "GND")
			(options
				(clearance outline)
				(anchor circle)
			)
			(primitives
				(gr_poly
					(pts
						(arc
							(start -0.1778 -0.2794)
							(mid -0.249642 -0.249642)
							(end -0.2794 -0.1778)
						)
						(arc
							(start -0.2794 0.1778)
							(mid -0.249642 0.249642)
							(end -0.1778 0.2794)
						)
						(arc
							(start 0.1778 0.2794)
							(mid 0.249642 0.249642)
							(end 0.2794 0.1778)
						)
						(arc
							(start 0.2794 -0.1778)
							(mid 0.249642 -0.249642)
							(end 0.1778 -0.2794)
						)
					)
					(width 0)
					(fill yes)
				)
			)
		)
	)
	(footprint ""
		(layer "F.Cu")
		(at 190.960756 -492.179102 -90)
		(property "Reference" "R107"
			(at 0 0 270)
			(layer "F.SilkS")
			(hide yes)
			(effects
				(font
					(size 1.27 1.27)
				)
			)
		)
		(property "Value" "1KR2F-3-GP"
			(at 0.064008 -3.993896 270)
			(unlocked yes)
			(layer "F.Fab")
			(hide yes)
			(effects
				(font
					(size 1.016 1.016)
					(thickness 0.1524)
				)
			)
		)
		(property "Device Type" "R402H16"
			(at 0.064008 -5.517896 270)
			(unlocked yes)
			(layer "F.Fab")
			(hide yes)
			(effects
				(font
					(size 1.016 1.016)
					(thickness 0.1524)
				)
			)
		)
		(duplicate_pad_numbers_are_jumpers no)
		(fp_line
			(start -0.508 -0.9398)
			(end -0.508 0.9398)
			(stroke
				(width 0.1524)
				(type default)
			)
			(layer "F.SilkS")
		)
		(fp_line
			(start 0.508 -0.9398)
			(end -0.508 -0.9398)
			(stroke
				(width 0.1524)
				(type default)
			)
			(layer "F.SilkS")
		)
		(fp_rect
			(start -0.508 0.9398)
			(end 0.508 -0.9398)
			(stroke
				(width 0)
				(type default)
			)
			(fill no)
			(layer "F.CrtYd")
		)
		(fp_rect
			(start -0.508 0.9398)
			(end 0.508 -0.9398)
			(stroke
				(width 0)
				(type default)
			)
			(fill no)
			(layer "F.Fab")
		)
		(pad "1" smd custom
			(at 0 -0.4445 270)
			(size 0.1397 0.1397)
			(layers "F.Cu" "F.Mask" "F.Paste")
			(net "P3V3")
			(options
				(clearance outline)
				(anchor circle)
			)
			(primitives
				(gr_poly
					(pts
						(arc
							(start -0.1778 -0.2794)
							(mid -0.249642 -0.249642)
							(end -0.2794 -0.1778)
						)
						(arc
							(start -0.2794 0.1778)
							(mid -0.249642 0.249642)
							(end -0.1778 0.2794)
						)
						(arc
							(start 0.1778 0.2794)
							(mid 0.249642 0.249642)
							(end 0.2794 0.1778)
						)
						(arc
							(start 0.2794 -0.1778)
							(mid 0.249642 -0.249642)
							(end 0.1778 -0.2794)
						)
					)
					(width 0)
					(fill yes)
				)
			)
		)
		(pad "2" smd custom
			(at 0 0.4445 270)
			(size 0.1397 0.1397)
			(layers "F.Cu" "F.Mask" "F.Paste")
			(net "SW_PWR_HDD0")
			(options
				(clearance outline)
				(anchor circle)
			)
			(primitives
				(gr_poly
					(pts
						(arc
							(start -0.1778 -0.2794)
							(mid -0.249642 -0.249642)
							(end -0.2794 -0.1778)
						)
						(arc
							(start -0.2794 0.1778)
							(mid -0.249642 0.249642)
							(end -0.1778 0.2794)
						)
						(arc
							(start 0.1778 0.2794)
							(mid 0.249642 0.249642)
							(end 0.2794 0.1778)
						)
						(arc
							(start 0.2794 -0.1778)
							(mid 0.249642 -0.249642)
							(end 0.1778 -0.2794)
						)
					)
					(width 0)
					(fill yes)
				)
			)
		)
	)
)
